(kicad_pcb
	(version 20260206)
	(generator "pcbnew")
	(generator_version "10.0")
	(general
		(thickness 1.6)
		(legacy_teardrops no)
	)
	(paper "A4")
	(title_block
		(title "12092022_DA0F0TYB4D0_F0T_Panel_BD_Front_D_brd_v02_OCP.brd")
		(comment 1 "Grand Teton / footprints 44-49 of 128")
	)
	(layers
		(0 "F.Cu" signal "TOP")
		(4 "In1.Cu" signal "GND")
		(6 "In2.Cu" signal "GND1")
		(2 "B.Cu" signal "BOTTOM")
		(9 "F.Adhes" user "F.Adhesive")
		(11 "B.Adhes" user "B.Adhesive")
		(13 "F.Paste" user "Package Geometry/Pastemask Top")
		(15 "B.Paste" user "Package Geometry/Pastemask Bottom")
		(5 "F.SilkS" user "Ref Des/Silkscreen Top")
		(7 "B.SilkS" user "Ref Des/Silkscreen Bottom")
		(1 "F.Mask" user "Board Geometry/Soldermask Top")
		(3 "B.Mask" user "Board Geometry/Soldermask Bottom")
		(17 "Dwgs.User" user "User.Drawings")
		(19 "Cmts.User" user "User.Comments")
		(21 "Eco1.User" user "User.Eco1")
		(23 "Eco2.User" user "User.Eco2")
		(25 "Edge.Cuts" user "Board Geometry/Outline")
		(27 "Margin" user)
		(31 "F.CrtYd" user "Package Geometry/Place Bound Top")
		(29 "B.CrtYd" user "Package Geometry/Place Bound Bottom")
		(35 "F.Fab" user "Ref Des/Assembly Top")
		(33 "B.Fab" user "Ref Des/Assembly Bottom")
	)
	(footprint ""
		(layer "F.Cu")
		(at 15.621 -67.437 180)
		(property "Reference" "C4"
			(at 2.159 -0.02667 0)
			(unlocked yes)
			(layer "F.SilkS")
			(effects
				(font
					(size 0.7874 0.5842)
					(thickness 0.1524)
				)
			)
		)
		(property "Value" ""
			(at 0 0 180)
			(layer "F.Fab")
			(effects
				(font
					(size 1.27 1.27)
				)
			)
		)
		(duplicate_pad_numbers_are_jumpers no)
		(fp_line
			(start 0.7874 0.4064)
			(end -0.7874 0.4064)
			(stroke
				(width 0.1524)
				(type default)
			)
			(layer "F.SilkS")
		)
		(fp_line
			(start 0.7874 -0.4064)
			(end 0.7874 0.4064)
			(stroke
				(width 0.1524)
				(type default)
			)
			(layer "F.SilkS")
		)
		(fp_line
			(start -0.7874 0.4064)
			(end -0.7874 -0.4064)
			(stroke
				(width 0.1524)
				(type default)
			)
			(layer "F.SilkS")
		)
		(fp_line
			(start -0.7874 -0.4064)
			(end 0.7874 -0.4064)
			(stroke
				(width 0.1524)
				(type default)
			)
			(layer "F.SilkS")
		)
		(fp_line
			(start 0.67945 0.3048)
			(end 0.120396 0.3048)
			(stroke
				(width 0.1)
				(type default)
			)
			(layer "F.Fab")
		)
		(fp_line
			(start 0.67945 -0.3048)
			(end 0.67945 0.3048)
			(stroke
				(width 0.1)
				(type default)
			)
			(layer "F.Fab")
		)
		(fp_line
			(start 0.12065 -0.2794)
			(end 0.12065 -0.3048)
			(stroke
				(width 0.1)
				(type default)
			)
			(layer "F.Fab")
		)
		(fp_line
			(start 0.12065 -0.3048)
			(end 0.67945 -0.3048)
			(stroke
				(width 0.1)
				(type default)
			)
			(layer "F.Fab")
		)
		(fp_line
			(start 0.120396 0.3048)
			(end 0.120396 0.2794)
			(stroke
				(width 0.1)
				(type default)
			)
			(layer "F.Fab")
		)
		(fp_line
			(start 0.120396 0.2794)
			(end -0.12065 0.2794)
			(stroke
				(width 0.1)
				(type default)
			)
			(layer "F.Fab")
		)
		(fp_line
			(start -0.12065 0.3048)
			(end -0.67945 0.3048)
			(stroke
				(width 0.1)
				(type default)
			)
			(layer "F.Fab")
		)
		(fp_line
			(start -0.12065 0.2794)
			(end -0.12065 0.3048)
			(stroke
				(width 0.1)
				(type default)
			)
			(layer "F.Fab")
		)
		(fp_line
			(start -0.12065 -0.2794)
			(end 0.12065 -0.2794)
			(stroke
				(width 0.1)
				(type default)
			)
			(layer "F.Fab")
		)
		(fp_line
			(start -0.12065 -0.305054)
			(end -0.12065 -0.2794)
			(stroke
				(width 0.1)
				(type default)
			)
			(layer "F.Fab")
		)
		(fp_line
			(start -0.67945 0.3048)
			(end -0.67945 -0.305054)
			(stroke
				(width 0.1)
				(type default)
			)
			(layer "F.Fab")
		)
		(fp_line
			(start -0.67945 -0.305054)
			(end -0.12065 -0.305054)
			(stroke
				(width 0.1)
				(type default)
			)
			(layer "F.Fab")
		)
		(pad "1" smd circle
			(at -0.40005 0 180)
			(size 0 0)
			(layers "F.Cu" "F.Mask" "F.Paste")
			(net "P5V_STBY")
		)
		(pad "2" smd circle
			(at 0.40005 0 180)
			(size 0 0)
			(layers "F.Cu" "F.Mask" "F.Paste")
			(net "GND")
		)
	)
	(footprint ""
		(layer "F.Cu")
		(at 18.415 -56.769)
		(property "Reference" "R15"
			(at 3.81 0.02667 0)
			(unlocked yes)
			(layer "F.SilkS")
			(effects
				(font
					(size 0.7874 0.5842)
					(thickness 0.1524)
				)
			)
		)
		(property "Value" ""
			(at 0 0 0)
			(layer "F.Fab")
			(effects
				(font
					(size 1.27 1.27)
				)
			)
		)
		(duplicate_pad_numbers_are_jumpers no)
		(fp_line
			(start -0.7874 -0.4064)
			(end 0.7874 -0.4064)
			(stroke
				(width 0.1524)
				(type default)
			)
			(layer "F.SilkS")
		)
		(fp_line
			(start -0.7874 0.4064)
			(end -0.7874 -0.4064)
			(stroke
				(width 0.1524)
				(type default)
			)
			(layer "F.SilkS")
		)
		(fp_line
			(start 0.7874 -0.4064)
			(end 0.7874 0.4064)
			(stroke
				(width 0.1524)
				(type default)
			)
			(layer "F.SilkS")
		)
		(fp_line
			(start 0.7874 0.4064)
			(end -0.7874 0.4064)
			(stroke
				(width 0.1524)
				(type default)
			)
			(layer "F.SilkS")
		)
		(fp_line
			(start -0.67945 -0.305054)
			(end -0.12065 -0.305054)
			(stroke
				(width 0.1)
				(type default)
			)
			(layer "F.Fab")
		)
		(fp_line
			(start -0.67945 0.3048)
			(end -0.67945 -0.305054)
			(stroke
				(width 0.1)
				(type default)
			)
			(layer "F.Fab")
		)
		(fp_line
			(start -0.12065 -0.305054)
			(end -0.12065 -0.2794)
			(stroke
				(width 0.1)
				(type default)
			)
			(layer "F.Fab")
		)
		(fp_line
			(start -0.12065 -0.2794)
			(end 0.12065 -0.2794)
			(stroke
				(width 0.1)
				(type default)
			)
			(layer "F.Fab")
		)
		(fp_line
			(start -0.12065 0.2794)
			(end -0.12065 0.3048)
			(stroke
				(width 0.1)
				(type default)
			)
			(layer "F.Fab")
		)
		(fp_line
			(start -0.12065 0.3048)
			(end -0.67945 0.3048)
			(stroke
				(width 0.1)
				(type default)
			)
			(layer "F.Fab")
		)
		(fp_line
			(start 0.120396 0.2794)
			(end -0.12065 0.2794)
			(stroke
				(width 0.1)
				(type default)
			)
			(layer "F.Fab")
		)
		(fp_line
			(start 0.120396 0.3048)
			(end 0.120396 0.2794)
			(stroke
				(width 0.1)
				(type default)
			)
			(layer "F.Fab")
		)
		(fp_line
			(start 0.12065 -0.3048)
			(end 0.67945 -0.3048)
			(stroke
				(width 0.1)
				(type default)
			)
			(layer "F.Fab")
		)
		(fp_line
			(start 0.12065 -0.2794)
			(end 0.12065 -0.3048)
			(stroke
				(width 0.1)
				(type default)
			)
			(layer "F.Fab")
		)
		(fp_line
			(start 0.67945 -0.3048)
			(end 0.67945 0.3048)
			(stroke
				(width 0.1)
				(type default)
			)
			(layer "F.Fab")
		)
		(fp_line
			(start 0.67945 0.3048)
			(end 0.120396 0.3048)
			(stroke
				(width 0.1)
				(type default)
			)
			(layer "F.Fab")
		)
		(pad "1" smd circle
			(at -0.40005 0)
			(size 0 0)
			(layers "F.Cu" "F.Mask" "F.Paste")
			(net "PWR_LED")
		)
		(pad "2" smd circle
			(at 0.40005 0)
			(size 0 0)
			(layers "F.Cu" "F.Mask" "F.Paste")
			(net "PWR_LED_R1")
		)
	)
	(footprint ""
		(layer "F.Cu")
		(at 19.558 -25.146)
		(property "Reference" "R31"
			(at 0.381 -4.16433 0)
			(unlocked yes)
			(layer "F.SilkS")
			(effects
				(font
					(size 0.7874 0.5842)
					(thickness 0.1524)
				)
			)
		)
		(property "Value" ""
			(at 0 0 0)
			(layer "F.Fab")
			(effects
				(font
					(size 1.27 1.27)
				)
			)
		)
		(duplicate_pad_numbers_are_jumpers no)
		(fp_line
			(start -0.7874 -0.4064)
			(end 0.7874 -0.4064)
			(stroke
				(width 0.1524)
				(type default)
			)
			(layer "F.SilkS")
		)
		(fp_line
			(start -0.7874 0.4064)
			(end -0.7874 -0.4064)
			(stroke
				(width 0.1524)
				(type default)
			)
			(layer "F.SilkS")
		)
		(fp_line
			(start 0.7874 -0.4064)
			(end 0.7874 0.4064)
			(stroke
				(width 0.1524)
				(type default)
			)
			(layer "F.SilkS")
		)
		(fp_line
			(start 0.7874 0.4064)
			(end -0.7874 0.4064)
			(stroke
				(width 0.1524)
				(type default)
			)
			(layer "F.SilkS")
		)
		(fp_line
			(start -0.67945 -0.305054)
			(end -0.12065 -0.305054)
			(stroke
				(width 0.1)
				(type default)
			)
			(layer "F.Fab")
		)
		(fp_line
			(start -0.67945 0.3048)
			(end -0.67945 -0.305054)
			(stroke
				(width 0.1)
				(type default)
			)
			(layer "F.Fab")
		)
		(fp_line
			(start -0.12065 -0.305054)
			(end -0.12065 -0.2794)
			(stroke
				(width 0.1)
				(type default)
			)
			(layer "F.Fab")
		)
		(fp_line
			(start -0.12065 -0.2794)
			(end 0.12065 -0.2794)
			(stroke
				(width 0.1)
				(type default)
			)
			(layer "F.Fab")
		)
		(fp_line
			(start -0.12065 0.2794)
			(end -0.12065 0.3048)
			(stroke
				(width 0.1)
				(type default)
			)
			(layer "F.Fab")
		)
		(fp_line
			(start -0.12065 0.3048)
			(end -0.67945 0.3048)
			(stroke
				(width 0.1)
				(type default)
			)
			(layer "F.Fab")
		)
		(fp_line
			(start 0.120396 0.2794)
			(end -0.12065 0.2794)
			(stroke
				(width 0.1)
				(type default)
			)
			(layer "F.Fab")
		)
		(fp_line
			(start 0.120396 0.3048)
			(end 0.120396 0.2794)
			(stroke
				(width 0.1)
				(type default)
			)
			(layer "F.Fab")
		)
		(fp_line
			(start 0.12065 -0.3048)
			(end 0.67945 -0.3048)
			(stroke
				(width 0.1)
				(type default)
			)
			(layer "F.Fab")
		)
		(fp_line
			(start 0.12065 -0.2794)
			(end 0.12065 -0.3048)
			(stroke
				(width 0.1)
				(type default)
			)
			(layer "F.Fab")
		)
		(fp_line
			(start 0.67945 -0.3048)
			(end 0.67945 0.3048)
			(stroke
				(width 0.1)
				(type default)
			)
			(layer "F.Fab")
		)
		(fp_line
			(start 0.67945 0.3048)
			(end 0.120396 0.3048)
			(stroke
				(width 0.1)
				(type default)
			)
			(layer "F.Fab")
		)
		(pad "1" smd circle
			(at -0.40005 0)
			(size 0 0)
			(layers "F.Cu" "F.Mask" "F.Paste")
			(net "P3V3_STBY")
		)
		(pad "2" smd circle
			(at 0.40005 0)
			(size 0 0)
			(layers "F.Cu" "F.Mask" "F.Paste")
			(net "SMB_TMP75_SDA")
		)
	)
	(footprint ""
		(layer "F.Cu")
		(at 6.599936 -70.980046 180)
		(property "Reference" "H12"
			(at -3.052064 7.098284 0)
			(unlocked yes)
			(layer "F.SilkS")
			(effects
				(font
					(size 0.7874 0.5842)
					(thickness 0.1524)
				)
				(justify left)
			)
		)
		(property "Value" ""
			(at 0 0 180)
			(layer "F.Fab")
			(effects
				(font
					(size 1.27 1.27)
				)
			)
		)
		(duplicate_pad_numbers_are_jumpers no)
		(fp_line
			(start 4.126992 0)
			(end 4.126992 3.50012)
			(stroke
				(width 0.1524)
				(type default)
			)
			(layer "F.SilkS")
		)
		(fp_line
			(start -4.126992 3.50012)
			(end -4.126992 0)
			(stroke
				(width 0.1524)
				(type default)
			)
			(layer "F.SilkS")
		)
		(fp_arc
			(start 4.126992 3.50012)
			(mid 0 7.627112)
			(end -4.126992 3.50012)
			(stroke
				(width 0.1524)
				(type default)
			)
			(layer "F.SilkS")
		)
		(fp_arc
			(start -4.126992 0)
			(mid 0 -4.126992)
			(end 4.126992 0)
			(stroke
				(width 0.1524)
				(type default)
			)
			(layer "F.SilkS")
		)
		(fp_line
			(start 4.126992 0)
			(end 4.126992 3.50012)
			(stroke
				(width 0.1524)
				(type default)
			)
			(layer "B.SilkS")
		)
		(fp_line
			(start -4.126992 3.50012)
			(end -4.126992 0)
			(stroke
				(width 0.1524)
				(type default)
			)
			(layer "B.SilkS")
		)
		(fp_arc
			(start 4.126992 3.50012)
			(mid 0 7.627112)
			(end -4.126992 3.50012)
			(stroke
				(width 0.1524)
				(type default)
			)
			(layer "B.SilkS")
		)
		(fp_arc
			(start -4.126992 0)
			(mid 0 -4.126992)
			(end 4.126992 0)
			(stroke
				(width 0.1524)
				(type default)
			)
			(layer "B.SilkS")
		)
		(fp_line
			(start 4.126992 0)
			(end 4.126992 3.50012)
			(stroke
				(width 0.1)
				(type default)
			)
			(layer "B.Fab")
		)
		(fp_line
			(start -4.126992 3.50012)
			(end -4.126992 0)
			(stroke
				(width 0.1)
				(type default)
			)
			(layer "B.Fab")
		)
		(fp_arc
			(start 4.126992 3.50012)
			(mid 0 7.627112)
			(end -4.126992 3.50012)
			(stroke
				(width 0.1)
				(type default)
			)
			(layer "B.Fab")
		)
		(fp_arc
			(start -4.126992 0)
			(mid 0 -4.126992)
			(end 4.126992 0)
			(stroke
				(width 0.1)
				(type default)
			)
			(layer "B.Fab")
		)
		(fp_line
			(start 4.126992 0)
			(end 4.126992 3.50012)
			(stroke
				(width 0.1)
				(type default)
			)
			(layer "F.Fab")
		)
		(fp_line
			(start -4.126992 3.50012)
			(end -4.126992 0)
			(stroke
				(width 0.1)
				(type default)
			)
			(layer "F.Fab")
		)
		(fp_arc
			(start 4.126992 3.50012)
			(mid 0 7.627112)
			(end -4.126992 3.50012)
			(stroke
				(width 0.1)
				(type default)
			)
			(layer "F.Fab")
		)
		(fp_arc
			(start -4.126992 0)
			(mid 0 -4.126992)
			(end 4.126992 0)
			(stroke
				(width 0.1)
				(type default)
			)
			(layer "F.Fab")
		)
		(pad "" np_thru_hole circle
			(at 0 0 180)
			(size 3.0226 3.0226)
			(drill 3.0226)
			(layers "*.Cu" "*.Mask")
			(clearance 0.381)
			(thermal_gap 0.381)
		)
		(zone
			(layers "F.Cu" "B.Cu" "In1.Cu" "In2.Cu")
			(hatch none 0.5)
			(connect_pads
				(clearance 0)
			)
			(min_thickness 0.25)
			(keepout
				(tracks not_allowed)
				(vias allowed)
				(pads allowed)
				(copperpour not_allowed)
				(footprints allowed)
			)
			(placement
				(enabled no)
				(sheetname "")
			)
			(fill
				(thermal_gap 0.5)
				(thermal_bridge_width 0.5)
				(island_removal_mode 0)
			)
			(polygon
				(pts
					(arc
						(start 4.260342 -72.58939)
						(mid 6.599936 -77.487864)
						(end 8.93953 -72.58939)
					)
					(arc
						(start 8.93953 -72.58939)
						(mid 8.693357 -72.148942)
						(end 8.60806 -71.651622)
					)
					(arc
						(start 8.60806 -70.980046)
						(mid 6.599936 -68.971922)
						(end 4.591812 -70.980046)
					)
					(arc
						(start 4.591812 -71.651622)
						(mid 4.506506 -72.148935)
						(end 4.260342 -72.58939)
					)
				)
			)
		)
	)
	(footprint ""
		(layer "F.Cu")
		(at 5.969 -62.357 180)
		(property "Reference" "R24"
			(at 2.667 -0.40767 0)
			(unlocked yes)
			(layer "F.SilkS")
			(effects
				(font
					(size 0.7874 0.5842)
					(thickness 0.1524)
				)
			)
		)
		(property "Value" ""
			(at 0 0 180)
			(layer "F.Fab")
			(effects
				(font
					(size 1.27 1.27)
				)
			)
		)
		(duplicate_pad_numbers_are_jumpers no)
		(fp_line
			(start 0.7874 0.4064)
			(end -0.7874 0.4064)
			(stroke
				(width 0.1524)
				(type default)
			)
			(layer "F.SilkS")
		)
		(fp_line
			(start 0.7874 -0.4064)
			(end 0.7874 0.4064)
			(stroke
				(width 0.1524)
				(type default)
			)
			(layer "F.SilkS")
		)
		(fp_line
			(start -0.7874 0.4064)
			(end -0.7874 -0.4064)
			(stroke
				(width 0.1524)
				(type default)
			)
			(layer "F.SilkS")
		)
		(fp_line
			(start -0.7874 -0.4064)
			(end 0.7874 -0.4064)
			(stroke
				(width 0.1524)
				(type default)
			)
			(layer "F.SilkS")
		)
		(fp_line
			(start 0.67945 0.3048)
			(end 0.120396 0.3048)
			(stroke
				(width 0.1)
				(type default)
			)
			(layer "F.Fab")
		)
		(fp_line
			(start 0.67945 -0.3048)
			(end 0.67945 0.3048)
			(stroke
				(width 0.1)
				(type default)
			)
			(layer "F.Fab")
		)
		(fp_line
			(start 0.12065 -0.2794)
			(end 0.12065 -0.3048)
			(stroke
				(width 0.1)
				(type default)
			)
			(layer "F.Fab")
		)
		(fp_line
			(start 0.12065 -0.3048)
			(end 0.67945 -0.3048)
			(stroke
				(width 0.1)
				(type default)
			)
			(layer "F.Fab")
		)
		(fp_line
			(start 0.120396 0.3048)
			(end 0.120396 0.2794)
			(stroke
				(width 0.1)
				(type default)
			)
			(layer "F.Fab")
		)
		(fp_line
			(start 0.120396 0.2794)
			(end -0.12065 0.2794)
			(stroke
				(width 0.1)
				(type default)
			)
			(layer "F.Fab")
		)
		(fp_line
			(start -0.12065 0.3048)
			(end -0.67945 0.3048)
			(stroke
				(width 0.1)
				(type default)
			)
			(layer "F.Fab")
		)
		(fp_line
			(start -0.12065 0.2794)
			(end -0.12065 0.3048)
			(stroke
				(width 0.1)
				(type default)
			)
			(layer "F.Fab")
		)
		(fp_line
			(start -0.12065 -0.2794)
			(end 0.12065 -0.2794)
			(stroke
				(width 0.1)
				(type default)
			)
			(layer "F.Fab")
		)
		(fp_line
			(start -0.12065 -0.305054)
			(end -0.12065 -0.2794)
			(stroke
				(width 0.1)
				(type default)
			)
			(layer "F.Fab")
		)
		(fp_line
			(start -0.67945 0.3048)
			(end -0.67945 -0.305054)
			(stroke
				(width 0.1)
				(type default)
			)
			(layer "F.Fab")
		)
		(fp_line
			(start -0.67945 -0.305054)
			(end -0.12065 -0.305054)
			(stroke
				(width 0.1)
				(type default)
			)
			(layer "F.Fab")
		)
		(pad "1" smd circle
			(at -0.40005 0 180)
			(size 0 0)
			(layers "F.Cu" "F.Mask" "F.Paste")
			(net "PCA9539_A1")
		)
		(pad "2" smd circle
			(at 0.40005 0 180)
			(size 0 0)
			(layers "F.Cu" "F.Mask" "F.Paste")
			(net "GND")
		)
	)
	(footprint ""
		(layer "F.Cu")
		(at 3.937 -51.816)
		(property "Reference" "R58"
			(at -2.413 0.15367 0)
			(unlocked yes)
			(layer "F.SilkS")
			(effects
				(font
					(size 0.7874 0.5842)
					(thickness 0.1524)
				)
			)
		)
		(property "Value" ""
			(at 0 0 0)
			(layer "F.Fab")
			(effects
				(font
					(size 1.27 1.27)
				)
			)
		)
		(duplicate_pad_numbers_are_jumpers no)
		(fp_line
			(start -0.7874 -0.4064)
			(end 0.7874 -0.4064)
			(stroke
				(width 0.1524)
				(type default)
			)
			(layer "F.SilkS")
		)
		(fp_line
			(start -0.7874 0.4064)
			(end -0.7874 -0.4064)
			(stroke
				(width 0.1524)
				(type default)
			)
			(layer "F.SilkS")
		)
		(fp_line
			(start 0.7874 -0.4064)
			(end 0.7874 0.4064)
			(stroke
				(width 0.1524)
				(type default)
			)
			(layer "F.SilkS")
		)
		(fp_line
			(start 0.7874 0.4064)
			(end -0.7874 0.4064)
			(stroke
				(width 0.1524)
				(type default)
			)
			(layer "F.SilkS")
		)
		(fp_line
			(start -0.67945 -0.305054)
			(end -0.12065 -0.305054)
			(stroke
				(width 0.1)
				(type default)
			)
			(layer "F.Fab")
		)
		(fp_line
			(start -0.67945 0.3048)
			(end -0.67945 -0.305054)
			(stroke
				(width 0.1)
				(type default)
			)
			(layer "F.Fab")
		)
		(fp_line
			(start -0.12065 -0.305054)
			(end -0.12065 -0.2794)
			(stroke
				(width 0.1)
				(type default)
			)
			(layer "F.Fab")
		)
		(fp_line
			(start -0.12065 -0.2794)
			(end 0.12065 -0.2794)
			(stroke
				(width 0.1)
				(type default)
			)
			(layer "F.Fab")
		)
		(fp_line
			(start -0.12065 0.2794)
			(end -0.12065 0.3048)
			(stroke
				(width 0.1)
				(type default)
			)
			(layer "F.Fab")
		)
		(fp_line
			(start -0.12065 0.3048)
			(end -0.67945 0.3048)
			(stroke
				(width 0.1)
				(type default)
			)
			(layer "F.Fab")
		)
		(fp_line
			(start 0.120396 0.2794)
			(end -0.12065 0.2794)
			(stroke
				(width 0.1)
				(type default)
			)
			(layer "F.Fab")
		)
		(fp_line
			(start 0.120396 0.3048)
			(end 0.120396 0.2794)
			(stroke
				(width 0.1)
				(type default)
			)
			(layer "F.Fab")
		)
		(fp_line
			(start 0.12065 -0.3048)
			(end 0.67945 -0.3048)
			(stroke
				(width 0.1)
				(type default)
			)
			(layer "F.Fab")
		)
		(fp_line
			(start 0.12065 -0.2794)
			(end 0.12065 -0.3048)
			(stroke
				(width 0.1)
				(type default)
			)
			(layer "F.Fab")
		)
		(fp_line
			(start 0.67945 -0.3048)
			(end 0.67945 0.3048)
			(stroke
				(width 0.1)
				(type default)
			)
			(layer "F.Fab")
		)
		(fp_line
			(start 0.67945 0.3048)
			(end 0.120396 0.3048)
			(stroke
				(width 0.1)
				(type default)
			)
			(layer "F.Fab")
		)
		(pad "1" smd circle
			(at -0.40005 0)
			(size 0 0)
			(layers "F.Cu" "F.Mask" "F.Paste")
			(net "P3V3_STBY")
		)
		(pad "2" smd circle
			(at 0.40005 0)
			(size 0 0)
			(layers "F.Cu" "F.Mask" "F.Paste")
			(net "PD_FRU_A0")
		)
	)
)
